(kicad_pcb
	(version 20241229)
	(generator "pcbnew")
	(generator_version "9.0")
	(general
		(thickness 1.6)
		(legacy_teardrops no)
	)
	(paper "A4")
	(title_block
		(title "LPDDR4 testbed")
		(date "2024-03-26")
		(rev "1.2.2")
		(comment 9 "footprint 1 of 66 (J1), pads 1-100 of 262")
	)
	(layers
		(0 "F.Cu" signal)
		(4 "In1.Cu" power)
		(6 "In2.Cu" power)
		(8 "In3.Cu" signal)
		(10 "In4.Cu" signal)
		(2 "B.Cu" signal)
		(9 "F.Adhes" user "F.Adhesive")
		(11 "B.Adhes" user "B.Adhesive")
		(13 "F.Paste" user)
		(15 "B.Paste" user)
		(5 "F.SilkS" user "F.Silkscreen")
		(7 "B.SilkS" user "B.Silkscreen")
		(1 "F.Mask" user)
		(3 "B.Mask" user)
		(17 "Dwgs.User" user "User.Drawings")
		(19 "Cmts.User" user "User.Comments")
		(21 "Eco1.User" user "User.Eco1")
		(23 "Eco2.User" user "User.Eco2")
		(25 "Edge.Cuts" user)
		(27 "Margin" user)
		(31 "F.CrtYd" user "F.Courtyard")
		(29 "B.CrtYd" user "B.Courtyard")
		(35 "F.Fab" user)
		(33 "B.Fab" user)
	)
	(footprint "antmicro-footprints:Edge_Conn_Bus_DDR4"
		(locked yes)
		(layer "F.Cu")
		(at 100 100)
		(descr "SODIMM DDR4 Edge Connector")
		(tags "SODIMM DDR4 Edge Connector")
		(property "Reference" "J1"
			(at 0 -4.2 0)
			(layer "F.SilkS")
			(hide yes)
			(effects
				(font
					(size 0.7 0.7)
					(thickness 0.15)
				)
				(justify left bottom)
			)
		)
		(property "Value" "Bus_DDR4_Edge_Conn"
			(at 0 1 0)
			(layer "F.Fab")
			(effects
				(font
					(size 0.7 0.7)
					(thickness 0.15)
				)
				(justify left bottom)
			)
		)
		(property "Description" "DDR SO-DIMM PCB Edge"
			(at 0 0 0)
			(layer "F.Fab")
			(hide yes)
			(effects
				(font
					(size 1.27 1.27)
					(thickness 0.15)
				)
			)
		)
		(property "Author" "Antmicro"
			(at 0 0 0)
			(layer "F.Fab")
			(hide yes)
			(effects
				(font
					(size 1 1)
					(thickness 0.15)
				)
			)
		)
		(property "License" "Apache-2.0"
			(at 0 0 0)
			(layer "F.Fab")
			(hide yes)
			(effects
				(font
					(size 1 1)
					(thickness 0.15)
				)
			)
		)
		(property "MPN" ""
			(at 0 0 0)
			(layer "F.Fab")
			(hide yes)
			(effects
				(font
					(size 1 1)
					(thickness 0.15)
				)
			)
		)
		(property "Manufacturer" ""
			(at 0 0 0)
			(layer "F.Fab")
			(hide yes)
			(effects
				(font
					(size 1 1)
					(thickness 0.15)
				)
			)
		)
		(sheetname "SODIMM")
		(sheetfile "sodim.kicad_sch")
		(attr exclude_from_pos_files exclude_from_bom)
		(pad "" np_thru_hole circle
			(at 1.999 -6)
			(size 1.8 1.8)
			(drill 1.8)
			(layers "*.Cu" "*.Mask")
		)
		(pad "" np_thru_hole circle
			(at 67.599 -6)
			(size 1.8 1.8)
			(drill 1.8)
			(layers "*.Cu" "*.Mask")
		)
		(pad "1" smd rect
			(at 1.425 -1.301)
			(size 0.35 2.5)
			(layers "F.Cu" "F.Mask")
			(net 36 "GND")
			(pinfunction "1")
			(pintype "passive")
		)
		(pad "2" smd rect
			(at 1.675 -1.301)
			(size 0.35 2.5)
			(layers "B.Cu" "B.Mask")
			(net 36 "GND")
			(pinfunction "2")
			(pintype "passive")
		)
		(pad "3" smd rect
			(at 1.925 -1.301)
			(size 0.35 2.5)
			(layers "F.Cu" "F.Mask")
			(net 36 "GND")
			(pinfunction "3")
			(pintype "passive")
		)
		(pad "4" smd rect
			(at 2.173 -1.301)
			(size 0.35 2.5)
			(layers "B.Cu" "B.Mask")
			(net 36 "GND")
			(pinfunction "4")
			(pintype "passive")
		)
		(pad "5" smd rect
			(at 2.423 -1.301)
			(size 0.35 2.5)
			(layers "F.Cu" "F.Mask")
			(net 36 "GND")
			(pinfunction "5")
			(pintype "passive")
		)
		(pad "6" smd rect
			(at 2.673 -1.301)
			(size 0.35 2.5)
			(layers "B.Cu" "B.Mask")
			(net 36 "GND")
			(pinfunction "6")
			(pintype "passive")
		)
		(pad "7" smd rect
			(at 2.923 -1.301)
			(size 0.35 2.5)
			(layers "F.Cu" "F.Mask")
			(net 36 "GND")
			(pinfunction "7")
			(pintype "passive")
		)
		(pad "8" smd rect
			(at 3.173 -1.301)
			(size 0.35 2.5)
			(layers "B.Cu" "B.Mask")
			(net 36 "GND")
			(pinfunction "8")
			(pintype "passive")
		)
		(pad "9" smd rect
			(at 3.423 -1.301)
			(size 0.35 2.5)
			(layers "F.Cu" "F.Mask")
			(net 36 "GND")
			(pinfunction "9")
			(pintype "passive")
		)
		(pad "10" smd rect
			(at 3.673 -1.301)
			(size 0.35 2.5)
			(layers "B.Cu" "B.Mask")
			(net 36 "GND")
			(pinfunction "10")
			(pintype "passive")
		)
		(pad "11" smd rect
			(at 3.923 -1.301)
			(size 0.35 2.5)
			(layers "F.Cu" "F.Mask")
			(net 36 "GND")
			(pinfunction "11")
			(pintype "passive")
		)
		(pad "12" smd rect
			(at 4.174 -1.301)
			(size 0.35 2.5)
			(layers "B.Cu" "B.Mask")
			(net 36 "GND")
			(pinfunction "12")
			(pintype "passive")
		)
		(pad "13" smd rect
			(at 4.424 -1.301)
			(size 0.35 2.5)
			(layers "F.Cu" "F.Mask")
			(net 36 "GND")
			(pinfunction "13")
			(pintype "passive")
		)
		(pad "14" smd rect
			(at 4.674 -1.301)
			(size 0.35 2.5)
			(layers "B.Cu" "B.Mask")
			(net 36 "GND")
			(pinfunction "14")
			(pintype "passive")
		)
		(pad "15" smd rect
			(at 4.924 -1.301)
			(size 0.35 2.5)
			(layers "F.Cu" "F.Mask")
			(net 36 "GND")
			(pinfunction "15")
			(pintype "passive")
		)
		(pad "16" smd rect
			(at 5.174 -1.301)
			(size 0.35 2.5)
			(layers "B.Cu" "B.Mask")
			(net 36 "GND")
			(pinfunction "16")
			(pintype "passive")
		)
		(pad "17" smd rect
			(at 5.424 -1.301)
			(size 0.35 2.5)
			(layers "F.Cu" "F.Mask")
			(net 36 "GND")
			(pinfunction "17")
			(pintype "passive")
		)
		(pad "18" smd rect
			(at 5.674 -1.301)
			(size 0.35 2.5)
			(layers "B.Cu" "B.Mask")
			(net 36 "GND")
			(pinfunction "18")
			(pintype "passive")
		)
		(pad "19" smd rect
			(at 5.924 -1.301)
			(size 0.35 2.5)
			(layers "F.Cu" "F.Mask")
			(net 36 "GND")
			(pinfunction "19")
			(pintype "passive")
		)
		(pad "20" smd rect
			(at 6.174 -1.301)
			(size 0.35 2.5)
			(layers "B.Cu" "B.Mask")
			(net 36 "GND")
			(pinfunction "20")
			(pintype "passive")
		)
		(pad "21" smd rect
			(at 6.424 -1.301)
			(size 0.35 2.5)
			(layers "F.Cu" "F.Mask")
			(net 36 "GND")
			(pinfunction "21")
			(pintype "passive")
		)
		(pad "22" smd rect
			(at 6.674 -1.301)
			(size 0.35 2.5)
			(layers "B.Cu" "B.Mask")
			(net 36 "GND")
			(pinfunction "22")
			(pintype "passive")
		)
		(pad "23" smd rect
			(at 6.924 -1.301)
			(size 0.35 2.5)
			(layers "F.Cu" "F.Mask")
			(net 36 "GND")
			(pinfunction "23")
			(pintype "passive")
		)
		(pad "24" smd rect
			(at 7.174 -1.301)
			(size 0.35 2.5)
			(layers "B.Cu" "B.Mask")
			(net 36 "GND")
			(pinfunction "24")
			(pintype "passive")
		)
		(pad "25" smd rect
			(at 7.424 -1.301)
			(size 0.35 2.5)
			(layers "F.Cu" "F.Mask")
			(net 36 "GND")
			(pinfunction "25")
			(pintype "passive")
		)
		(pad "26" smd rect
			(at 7.674 -1.301)
			(size 0.35 2.5)
			(layers "B.Cu" "B.Mask")
			(net 36 "GND")
			(pinfunction "26")
			(pintype "passive")
		)
		(pad "27" smd rect
			(at 7.924 -1.301)
			(size 0.35 2.5)
			(layers "F.Cu" "F.Mask")
			(net 36 "GND")
			(pinfunction "27")
			(pintype "passive")
		)
		(pad "28" smd rect
			(at 8.175 -1.301)
			(size 0.35 2.5)
			(layers "B.Cu" "B.Mask")
			(net 36 "GND")
			(pinfunction "28")
			(pintype "passive")
		)
		(pad "29" smd rect
			(at 8.425 -1.301)
			(size 0.35 2.5)
			(layers "F.Cu" "F.Mask")
			(net 36 "GND")
			(pinfunction "29")
			(pintype "passive")
		)
		(pad "30" smd rect
			(at 8.675 -1.301)
			(size 0.35 2.5)
			(layers "B.Cu" "B.Mask")
			(net 36 "GND")
			(pinfunction "30")
			(pintype "passive")
		)
		(pad "31" smd rect
			(at 8.925 -1.301)
			(size 0.35 2.5)
			(layers "F.Cu" "F.Mask")
			(net 36 "GND")
			(pinfunction "31")
			(pintype "passive")
		)
		(pad "32" smd rect
			(at 9.175 -1.301)
			(size 0.35 2.5)
			(layers "B.Cu" "B.Mask")
			(net 36 "GND")
			(pinfunction "32")
			(pintype "passive")
		)
		(pad "33" smd rect
			(at 9.425 -1.301)
			(size 0.35 2.5)
			(layers "F.Cu" "F.Mask")
			(net 36 "GND")
			(pinfunction "33")
			(pintype "passive")
		)
		(pad "34" smd rect
			(at 9.675 -1.301)
			(size 0.35 2.5)
			(layers "B.Cu" "B.Mask")
			(net 36 "GND")
			(pinfunction "34")
			(pintype "passive")
		)
		(pad "35" smd rect
			(at 9.925 -1.301)
			(size 0.35 2.5)
			(layers "F.Cu" "F.Mask")
			(net 36 "GND")
			(pinfunction "35")
			(pintype "passive")
		)
		(pad "36" smd rect
			(at 10.175 -1.301)
			(size 0.35 2.5)
			(layers "B.Cu" "B.Mask")
			(net 36 "GND")
			(pinfunction "36")
			(pintype "passive")
		)
		(pad "37" smd rect
			(at 10.425 -1.301)
			(size 0.35 2.5)
			(layers "F.Cu" "F.Mask")
			(net 36 "GND")
			(pinfunction "37")
			(pintype "passive")
		)
		(pad "38" smd rect
			(at 10.675 -1.301)
			(size 0.35 2.5)
			(layers "B.Cu" "B.Mask")
			(net 36 "GND")
			(pinfunction "38")
			(pintype "passive")
		)
		(pad "39" smd rect
			(at 10.925 -1.301)
			(size 0.35 2.5)
			(layers "F.Cu" "F.Mask")
			(net 36 "GND")
			(pinfunction "39")
			(pintype "passive")
		)
		(pad "40" smd rect
			(at 11.175 -1.301)
			(size 0.35 2.5)
			(layers "B.Cu" "B.Mask")
			(net 36 "GND")
			(pinfunction "40")
			(pintype "passive")
		)
		(pad "41" smd rect
			(at 11.425 -1.301)
			(size 0.35 2.5)
			(layers "F.Cu" "F.Mask")
			(net 36 "GND")
			(pinfunction "41")
			(pintype "passive")
		)
		(pad "42" smd rect
			(at 11.675 -1.301)
			(size 0.35 2.5)
			(layers "B.Cu" "B.Mask")
			(net 36 "GND")
			(pinfunction "42")
			(pintype "passive")
		)
		(pad "43" smd rect
			(at 11.925 -1.301)
			(size 0.35 2.5)
			(layers "F.Cu" "F.Mask")
			(net 36 "GND")
			(pinfunction "43")
			(pintype "passive")
		)
		(pad "44" smd rect
			(at 12.175 -1.301)
			(size 0.35 2.5)
			(layers "B.Cu" "B.Mask")
			(net 36 "GND")
			(pinfunction "44")
			(pintype "passive")
		)
		(pad "45" smd rect
			(at 12.425 -1.301)
			(size 0.35 2.5)
			(layers "F.Cu" "F.Mask")
			(net 36 "GND")
			(pinfunction "45")
			(pintype "passive")
		)
		(pad "46" smd rect
			(at 12.675 -1.301)
			(size 0.35 2.5)
			(layers "B.Cu" "B.Mask")
			(net 36 "GND")
			(pinfunction "46")
			(pintype "passive")
		)
		(pad "47" smd rect
			(at 12.925 -1.301)
			(size 0.35 2.5)
			(layers "F.Cu" "F.Mask")
			(net 36 "GND")
			(pinfunction "47")
			(pintype "passive")
		)
		(pad "48" smd rect
			(at 13.175 -1.301)
			(size 0.35 2.5)
			(layers "B.Cu" "B.Mask")
			(net 36 "GND")
			(pinfunction "48")
			(pintype "passive")
		)
		(pad "49" smd rect
			(at 13.425 -1.301)
			(size 0.35 2.5)
			(layers "F.Cu" "F.Mask")
			(net 36 "GND")
			(pinfunction "49")
			(pintype "passive")
		)
		(pad "50" smd rect
			(at 13.675 -1.301)
			(size 0.35 2.5)
			(layers "B.Cu" "B.Mask")
			(net 36 "GND")
			(pinfunction "50")
			(pintype "passive")
		)
		(pad "51" smd rect
			(at 13.925 -1.301)
			(size 0.35 2.5)
			(layers "F.Cu" "F.Mask")
			(net 4 "unconnected-(J1-Pad51)")
			(pinfunction "51")
			(pintype "passive+no_connect")
		)
		(pad "52" smd rect
			(at 14.175 -1.301)
			(size 0.35 2.5)
			(layers "B.Cu" "B.Mask")
			(net 5 "unconnected-(J1-Pad52)")
			(pinfunction "52")
			(pintype "passive+no_connect")
		)
		(pad "53" smd rect
			(at 14.425 -1.301)
			(size 0.35 2.5)
			(layers "F.Cu" "F.Mask")
			(net 6 "unconnected-(J1-Pad53)")
			(pinfunction "53")
			(pintype "passive+no_connect")
		)
		(pad "54" smd rect
			(at 14.675 -1.301)
			(size 0.35 2.5)
			(layers "B.Cu" "B.Mask")
			(net 7 "unconnected-(J1-Pad54)")
			(pinfunction "54")
			(pintype "passive+no_connect")
		)
		(pad "55" smd rect
			(at 14.925 -1.301)
			(size 0.35 2.5)
			(layers "F.Cu" "F.Mask")
			(net 8 "unconnected-(J1-Pad55)")
			(pinfunction "55")
			(pintype "passive+no_connect")
		)
		(pad "56" smd rect
			(at 15.175 -1.301)
			(size 0.35 2.5)
			(layers "B.Cu" "B.Mask")
			(net 9 "unconnected-(J1-Pad56)")
			(pinfunction "56")
			(pintype "passive+no_connect")
		)
		(pad "57" smd rect
			(at 15.425 -1.301)
			(size 0.35 2.5)
			(layers "F.Cu" "F.Mask")
			(net 10 "unconnected-(J1-Pad57)")
			(pinfunction "57")
			(pintype "passive+no_connect")
		)
		(pad "58" smd rect
			(at 15.675 -1.301)
			(size 0.35 2.5)
			(layers "B.Cu" "B.Mask")
			(net 11 "unconnected-(J1-Pad58)")
			(pinfunction "58")
			(pintype "passive+no_connect")
		)
		(pad "59" smd rect
			(at 15.925 -1.301)
			(size 0.35 2.5)
			(layers "F.Cu" "F.Mask")
			(net 12 "unconnected-(J1-Pad59)")
			(pinfunction "59")
			(pintype "passive+no_connect")
		)
		(pad "60" smd rect
			(at 16.175 -1.301)
			(size 0.35 2.5)
			(layers "B.Cu" "B.Mask")
			(net 13 "unconnected-(J1-Pad60)")
			(pinfunction "60")
			(pintype "passive+no_connect")
		)
		(pad "61" smd rect
			(at 16.425 -1.301)
			(size 0.35 2.5)
			(layers "F.Cu" "F.Mask")
			(net 14 "unconnected-(J1-Pad61)")
			(pinfunction "61")
			(pintype "passive+no_connect")
		)
		(pad "62" smd rect
			(at 16.675 -1.301)
			(size 0.35 2.5)
			(layers "B.Cu" "B.Mask")
			(net 15 "unconnected-(J1-Pad62)")
			(pinfunction "62")
			(pintype "passive+no_connect")
		)
		(pad "63" smd rect
			(at 16.925 -1.301)
			(size 0.35 2.5)
			(layers "F.Cu" "F.Mask")
			(net 16 "unconnected-(J1-Pad63)")
			(pinfunction "63")
			(pintype "passive+no_connect")
		)
		(pad "64" smd rect
			(at 17.175 -1.301)
			(size 0.35 2.5)
			(layers "B.Cu" "B.Mask")
			(net 17 "unconnected-(J1-Pad64)")
			(pinfunction "64")
			(pintype "passive+no_connect")
		)
		(pad "65" smd rect
			(at 17.425 -1.301)
			(size 0.35 2.5)
			(layers "F.Cu" "F.Mask")
			(net 18 "unconnected-(J1-Pad65)")
			(pinfunction "65")
			(pintype "passive+no_connect")
		)
		(pad "66" smd rect
			(at 17.675 -1.301)
			(size 0.35 2.5)
			(layers "B.Cu" "B.Mask")
			(net 19 "unconnected-(J1-Pad66)")
			(pinfunction "66")
			(pintype "passive+no_connect")
		)
		(pad "67" smd rect
			(at 17.925 -1.301)
			(size 0.35 2.5)
			(layers "F.Cu" "F.Mask")
			(net 20 "unconnected-(J1-Pad67)")
			(pinfunction "67")
			(pintype "passive+no_connect")
		)
		(pad "68" smd rect
			(at 18.175 -1.301)
			(size 0.35 2.5)
			(layers "B.Cu" "B.Mask")
			(net 21 "unconnected-(J1-Pad68)")
			(pinfunction "68")
			(pintype "passive+no_connect")
		)
		(pad "69" smd rect
			(at 18.425 -1.301)
			(size 0.35 2.5)
			(layers "F.Cu" "F.Mask")
			(net 22 "unconnected-(J1-Pad69)")
			(pinfunction "69")
			(pintype "passive+no_connect")
		)
		(pad "70" smd rect
			(at 18.675 -1.301)
			(size 0.35 2.5)
			(layers "B.Cu" "B.Mask")
			(net 23 "unconnected-(J1-Pad70)")
			(pinfunction "70")
			(pintype "passive+no_connect")
		)
		(pad "71" smd rect
			(at 18.925 -1.301)
			(size 0.35 2.5)
			(layers "F.Cu" "F.Mask")
			(net 24 "unconnected-(J1-Pad71)")
			(pinfunction "71")
			(pintype "passive+no_connect")
		)
		(pad "72" smd rect
			(at 19.175 -1.301)
			(size 0.35 2.5)
			(layers "B.Cu" "B.Mask")
			(net 25 "unconnected-(J1-Pad72)")
			(pinfunction "72")
			(pintype "passive+no_connect")
		)
		(pad "73" smd rect
			(at 19.425 -1.301)
			(size 0.35 2.5)
			(layers "F.Cu" "F.Mask")
			(net 26 "unconnected-(J1-Pad73)")
			(pinfunction "73")
			(pintype "passive+no_connect")
		)
		(pad "74" smd rect
			(at 19.675 -1.301)
			(size 0.35 2.5)
			(layers "B.Cu" "B.Mask")
			(net 27 "unconnected-(J1-Pad74)")
			(pinfunction "74")
			(pintype "passive+no_connect")
		)
		(pad "75" smd rect
			(at 19.925 -1.301)
			(size 0.35 2.5)
			(layers "F.Cu" "F.Mask")
			(net 28 "unconnected-(J1-Pad75)")
			(pinfunction "75")
			(pintype "passive+no_connect")
		)
		(pad "76" smd rect
			(at 20.175 -1.301)
			(size 0.35 2.5)
			(layers "B.Cu" "B.Mask")
			(net 29 "unconnected-(J1-Pad76)")
			(pinfunction "76")
			(pintype "passive+no_connect")
		)
		(pad "77" smd rect
			(at 20.425 -1.301)
			(size 0.35 2.5)
			(layers "F.Cu" "F.Mask")
			(net 30 "unconnected-(J1-Pad77)")
			(pinfunction "77")
			(pintype "passive+no_connect")
		)
		(pad "78" smd rect
			(at 20.675 -1.301)
			(size 0.35 2.5)
			(layers "B.Cu" "B.Mask")
			(net 31 "unconnected-(J1-Pad78)")
			(pinfunction "78")
			(pintype "passive+no_connect")
		)
		(pad "79" smd rect
			(at 20.925 -1.301)
			(size 0.35 2.5)
			(layers "F.Cu" "F.Mask")
			(net 32 "unconnected-(J1-Pad79)")
			(pinfunction "79")
			(pintype "passive+no_connect")
		)
		(pad "80" smd rect
			(at 21.175 -1.301)
			(size 0.35 2.5)
			(layers "B.Cu" "B.Mask")
			(net 33 "unconnected-(J1-Pad80)")
			(pinfunction "80")
			(pintype "passive+no_connect")
		)
		(pad "81" smd rect
			(at 21.425 -1.301)
			(size 0.35 2.5)
			(layers "F.Cu" "F.Mask")
			(net 34 "unconnected-(J1-Pad81)")
			(pinfunction "81")
			(pintype "passive+no_connect")
		)
		(pad "82" smd rect
			(at 21.675 -1.301)
			(size 0.35 2.5)
			(layers "B.Cu" "B.Mask")
			(net 35 "unconnected-(J1-Pad82)")
			(pinfunction "82")
			(pintype "passive+no_connect")
		)
		(pad "83" smd rect
			(at 21.925 -1.301)
			(size 0.35 2.5)
			(layers "F.Cu" "F.Mask")
			(net 37 "unconnected-(J1-Pad83)")
			(pinfunction "83")
			(pintype "passive+no_connect")
		)
		(pad "84" smd rect
			(at 22.175 -1.301)
			(size 0.35 2.5)
			(layers "B.Cu" "B.Mask")
			(net 38 "unconnected-(J1-Pad84)")
			(pinfunction "84")
			(pintype "passive+no_connect")
		)
		(pad "85" smd rect
			(at 22.425 -1.301)
			(size 0.35 2.5)
			(layers "F.Cu" "F.Mask")
			(net 39 "unconnected-(J1-Pad85)")
			(pinfunction "85")
			(pintype "passive+no_connect")
		)
		(pad "86" smd rect
			(at 22.675 -1.301)
			(size 0.35 2.5)
			(layers "B.Cu" "B.Mask")
			(net 40 "unconnected-(J1-Pad86)")
			(pinfunction "86")
			(pintype "passive+no_connect")
		)
		(pad "87" smd rect
			(at 22.925 -1.301)
			(size 0.35 2.5)
			(layers "F.Cu" "F.Mask")
			(net 41 "unconnected-(J1-Pad87)")
			(pinfunction "87")
			(pintype "passive+no_connect")
		)
		(pad "88" smd rect
			(at 23.175 -1.301)
			(size 0.35 2.5)
			(layers "B.Cu" "B.Mask")
			(net 42 "unconnected-(J1-Pad88)")
			(pinfunction "88")
			(pintype "passive+no_connect")
		)
		(pad "89" smd rect
			(at 23.425 -1.301)
			(size 0.35 2.5)
			(layers "F.Cu" "F.Mask")
			(net 43 "unconnected-(J1-Pad89)")
			(pinfunction "89")
			(pintype "passive+no_connect")
		)
		(pad "90" smd rect
			(at 23.675 -1.301)
			(size 0.35 2.5)
			(layers "B.Cu" "B.Mask")
			(net 44 "unconnected-(J1-Pad90)")
			(pinfunction "90")
			(pintype "passive+no_connect")
		)
		(pad "91" smd rect
			(at 23.925 -1.301)
			(size 0.35 2.5)
			(layers "F.Cu" "F.Mask")
			(net 45 "unconnected-(J1-Pad91)")
			(pinfunction "91")
			(pintype "passive+no_connect")
		)
		(pad "92" smd rect
			(at 24.175 -1.301)
			(size 0.35 2.5)
			(layers "B.Cu" "B.Mask")
			(net 46 "unconnected-(J1-Pad92)")
			(pinfunction "92")
			(pintype "passive+no_connect")
		)
		(pad "93" smd rect
			(at 24.425 -1.301)
			(size 0.35 2.5)
			(layers "F.Cu" "F.Mask")
			(net 188 "VDD2")
			(pinfunction "93")
			(pintype "passive")
		)
		(pad "94" smd rect
			(at 24.675 -1.301)
			(size 0.35 2.5)
			(layers "B.Cu" "B.Mask")
			(net 47 "unconnected-(J1-Pad94)")
			(pinfunction "94")
			(pintype "passive+no_connect")
		)
		(pad "95" smd rect
			(at 24.925 -1.301)
			(size 0.35 2.5)
			(layers "F.Cu" "F.Mask")
			(net 188 "VDD2")
			(pinfunction "95")
			(pintype "passive")
		)
		(pad "96" smd rect
			(at 25.175 -1.301)
			(size 0.35 2.5)
			(layers "B.Cu" "B.Mask")
			(net 48 "unconnected-(J1-Pad96)")
			(pinfunction "96")
			(pintype "passive+no_connect")
		)
		(pad "97" smd rect
			(at 25.425 -1.301)
			(size 0.35 2.5)
			(layers "F.Cu" "F.Mask")
			(net 188 "VDD2")
			(pinfunction "97")
			(pintype "passive")
		)
		(pad "98" smd rect
			(at 25.675 -1.301)
			(size 0.35 2.5)
			(layers "B.Cu" "B.Mask")
			(net 49 "unconnected-(J1-Pad98)")
			(pinfunction "98")
			(pintype "passive+no_connect")
		)
	)
)
